# S9S_MB_2U (Grand Teton) — schematic netlist excerpt (pin names and nets, part order shuffled) for the footprints in the layout excerpt that follows; sources: Cadence DE-HDL packaged netlist, KiCad conversion of 03242023_DA0F0TMBIJ0_F0T_Motherboard_J_brd_V01_OCP.brd

R1932  Q_RES  33.2 1% CHIP  pkg 0402LF  page 14 : A = SMB_S3M_CPU0_PIROM_3V3AUX_SCL ; B = SMB_S3M_CPU0_PIROM_3V3AUX_SCL_1
C485  Q_CAP  47UF 4V 20% X6S  pkg C0805  page 79 : A = PVCCFA_EHV_FIVRA_CPU1 ; B = GND
R687  Q_RES  0 5% CHIP  pkg 0402LF  page 229 : A = I3C_SPD_DDRABCD_CPU0_SCL ; B = I3C_SPD_DDRABCD_CPU0_R_SCL

(kicad_pcb
	(version 20260206)
	(generator "pcbnew")
	(generator_version "10.0")
	(general
		(thickness 1.6)
		(legacy_teardrops no)
	)
	(paper "A4")
	(title_block
		(title "03242023_DA0F0TMBIJ0_F0T_Motherboard_J_brd_V01_OCP.brd")
		(comment 1 "Grand Teton / footprints 4791-4793 of 6105")
	)
	(layers
		(0 "F.Cu" signal "TOP")
		(4 "In1.Cu" signal "GND")
		(6 "In2.Cu" signal "IN1")
		(8 "In3.Cu" signal "GND1")
		(10 "In4.Cu" signal "IN2")
		(12 "In5.Cu" signal "GND2")
		(14 "In6.Cu" signal "IN3")
		(16 "In7.Cu" signal "GND3")
		(18 "In8.Cu" signal "VCC")
		(20 "In9.Cu" signal "VCC1")
		(22 "In10.Cu" signal "GND4")
		(24 "In11.Cu" signal "IN4")
		(26 "In12.Cu" signal "GND5")
		(28 "In13.Cu" signal "IN5")
		(30 "In14.Cu" signal "GND6")
		(32 "In15.Cu" signal "IN6")
		(34 "In16.Cu" signal "GND7")
		(2 "B.Cu" signal "BOTTOM")
		(9 "F.Adhes" user "F.Adhesive")
		(11 "B.Adhes" user "B.Adhesive")
		(13 "F.Paste" user "Package Geometry/Pastemask Top")
		(15 "B.Paste" user "Package Geometry/Pastemask Bottom")
		(5 "F.SilkS" user "Ref Des/Silkscreen Top")
		(7 "B.SilkS" user "Ref Des/Silkscreen Bottom")
		(1 "F.Mask" user "Board Geometry/Soldermask Top")
		(3 "B.Mask" user "Board Geometry/Soldermask Bottom")
		(17 "Dwgs.User" user "User.Drawings")
		(19 "Cmts.User" user "User.Comments")
		(21 "Eco1.User" user "User.Eco1")
		(23 "Eco2.User" user "User.Eco2")
		(25 "Edge.Cuts" user "Board Geometry/Outline")
		(27 "Margin" user)
		(31 "F.CrtYd" user "Package Geometry/Place Bound Top")
		(29 "B.CrtYd" user "Package Geometry/Place Bound Bottom")
		(35 "F.Fab" user "Ref Des/Assembly Top")
		(33 "B.Fab" user "Ref Des/Assembly Bottom")
	)
	(footprint ""
		(layer "B.Cu")
		(at 180.90388 -329.479148 180)
		(property "Reference" "R1932"
			(at 0 0 0)
			(layer "B.SilkS")
			(hide yes)
			(effects
				(font
					(size 1.27 1.27)
				)
				(justify mirror)
			)
		)
		(property "Value" ""
			(at 0 0 0)
			(layer "B.Fab")
			(effects
				(font
					(size 1.27 1.27)
				)
				(justify mirror)
			)
		)
		(duplicate_pad_numbers_are_jumpers no)
		(fp_line
			(start 0.7874 0.4064)
			(end 0.7874 -0.4064)
			(stroke
				(width 0.1524)
				(type default)
			)
			(layer "B.SilkS")
		)
		(fp_line
			(start 0.7874 -0.4064)
			(end -0.7874 -0.4064)
			(stroke
				(width 0.1524)
				(type default)
			)
			(layer "B.SilkS")
		)
		(fp_line
			(start -0.7874 0.4064)
			(end 0.7874 0.4064)
			(stroke
				(width 0.1524)
				(type default)
			)
			(layer "B.SilkS")
		)
		(fp_line
			(start -0.7874 -0.4064)
			(end -0.7874 0.4064)
			(stroke
				(width 0.1524)
				(type default)
			)
			(layer "B.SilkS")
		)
		(fp_line
			(start 0.67945 0.3048)
			(end 0.67945 -0.305054)
			(stroke
				(width 0.1)
				(type default)
			)
			(layer "B.Fab")
		)
		(fp_line
			(start 0.67945 -0.305054)
			(end 0.12065 -0.305054)
			(stroke
				(width 0.1)
				(type default)
			)
			(layer "B.Fab")
		)
		(fp_line
			(start 0.12065 0.3048)
			(end 0.67945 0.3048)
			(stroke
				(width 0.1)
				(type default)
			)
			(layer "B.Fab")
		)
		(fp_line
			(start 0.12065 0.2794)
			(end 0.12065 0.3048)
			(stroke
				(width 0.1)
				(type default)
			)
			(layer "B.Fab")
		)
		(fp_line
			(start 0.12065 -0.2794)
			(end -0.12065 -0.2794)
			(stroke
				(width 0.1)
				(type default)
			)
			(layer "B.Fab")
		)
		(fp_line
			(start 0.12065 -0.305054)
			(end 0.12065 -0.2794)
			(stroke
				(width 0.1)
				(type default)
			)
			(layer "B.Fab")
		)
		(fp_line
			(start -0.120396 0.3048)
			(end -0.120396 0.2794)
			(stroke
				(width 0.1)
				(type default)
			)
			(layer "B.Fab")
		)
		(fp_line
			(start -0.120396 0.2794)
			(end 0.12065 0.2794)
			(stroke
				(width 0.1)
				(type default)
			)
			(layer "B.Fab")
		)
		(fp_line
			(start -0.12065 -0.2794)
			(end -0.12065 -0.3048)
			(stroke
				(width 0.1)
				(type default)
			)
			(layer "B.Fab")
		)
		(fp_line
			(start -0.12065 -0.3048)
			(end -0.67945 -0.3048)
			(stroke
				(width 0.1)
				(type default)
			)
			(layer "B.Fab")
		)
		(fp_line
			(start -0.67945 0.3048)
			(end -0.120396 0.3048)
			(stroke
				(width 0.1)
				(type default)
			)
			(layer "B.Fab")
		)
		(fp_line
			(start -0.67945 -0.3048)
			(end -0.67945 0.3048)
			(stroke
				(width 0.1)
				(type default)
			)
			(layer "B.Fab")
		)
		(pad "1" smd circle
			(at 0.40005 0)
			(size 0 0)
			(layers "B.Cu" "B.Mask" "B.Paste")
			(net "SMB_S3M_CPU0_PIROM_3V3AUX_SCL")
		)
		(pad "2" smd circle
			(at -0.40005 0)
			(size 0 0)
			(layers "B.Cu" "B.Mask" "B.Paste")
			(net "SMB_S3M_CPU0_PIROM_3V3AUX_SCL_1")
		)
	)
	(footprint ""
		(layer "B.Cu")
		(at 336.494882 -187.387738 180)
		(property "Reference" "R687"
			(at 0 0 0)
			(layer "B.SilkS")
			(hide yes)
			(effects
				(font
					(size 1.27 1.27)
				)
				(justify mirror)
			)
		)
		(property "Value" ""
			(at 0 0 0)
			(layer "B.Fab")
			(effects
				(font
					(size 1.27 1.27)
				)
				(justify mirror)
			)
		)
		(duplicate_pad_numbers_are_jumpers no)
		(fp_line
			(start 0.7874 0.4064)
			(end 0.7874 -0.4064)
			(stroke
				(width 0.1524)
				(type default)
			)
			(layer "B.SilkS")
		)
		(fp_line
			(start 0.7874 -0.4064)
			(end -0.7874 -0.4064)
			(stroke
				(width 0.1524)
				(type default)
			)
			(layer "B.SilkS")
		)
		(fp_line
			(start -0.7874 0.4064)
			(end 0.7874 0.4064)
			(stroke
				(width 0.1524)
				(type default)
			)
			(layer "B.SilkS")
		)
		(fp_line
			(start -0.7874 -0.4064)
			(end -0.7874 0.4064)
			(stroke
				(width 0.1524)
				(type default)
			)
			(layer "B.SilkS")
		)
		(fp_line
			(start 0.67945 0.3048)
			(end 0.67945 -0.305054)
			(stroke
				(width 0.1)
				(type default)
			)
			(layer "B.Fab")
		)
		(fp_line
			(start 0.67945 -0.305054)
			(end 0.12065 -0.305054)
			(stroke
				(width 0.1)
				(type default)
			)
			(layer "B.Fab")
		)
		(fp_line
			(start 0.12065 0.3048)
			(end 0.67945 0.3048)
			(stroke
				(width 0.1)
				(type default)
			)
			(layer "B.Fab")
		)
		(fp_line
			(start 0.12065 0.2794)
			(end 0.12065 0.3048)
			(stroke
				(width 0.1)
				(type default)
			)
			(layer "B.Fab")
		)
		(fp_line
			(start 0.12065 -0.2794)
			(end -0.12065 -0.2794)
			(stroke
				(width 0.1)
				(type default)
			)
			(layer "B.Fab")
		)
		(fp_line
			(start 0.12065 -0.305054)
			(end 0.12065 -0.2794)
			(stroke
				(width 0.1)
				(type default)
			)
			(layer "B.Fab")
		)
		(fp_line
			(start -0.120396 0.3048)
			(end -0.120396 0.2794)
			(stroke
				(width 0.1)
				(type default)
			)
			(layer "B.Fab")
		)
		(fp_line
			(start -0.120396 0.2794)
			(end 0.12065 0.2794)
			(stroke
				(width 0.1)
				(type default)
			)
			(layer "B.Fab")
		)
		(fp_line
			(start -0.12065 -0.2794)
			(end -0.12065 -0.3048)
			(stroke
				(width 0.1)
				(type default)
			)
			(layer "B.Fab")
		)
		(fp_line
			(start -0.12065 -0.3048)
			(end -0.67945 -0.3048)
			(stroke
				(width 0.1)
				(type default)
			)
			(layer "B.Fab")
		)
		(fp_line
			(start -0.67945 0.3048)
			(end -0.120396 0.3048)
			(stroke
				(width 0.1)
				(type default)
			)
			(layer "B.Fab")
		)
		(fp_line
			(start -0.67945 -0.3048)
			(end -0.67945 0.3048)
			(stroke
				(width 0.1)
				(type default)
			)
			(layer "B.Fab")
		)
		(pad "1" smd circle
			(at 0.40005 0)
			(size 0 0)
			(layers "B.Cu" "B.Mask" "B.Paste")
			(net "I3C_SPD_DDRABCD_CPU0_SCL")
		)
		(pad "2" smd circle
			(at -0.40005 0)
			(size 0 0)
			(layers "B.Cu" "B.Mask" "B.Paste")
			(net "I3C_SPD_DDRABCD_CPU0_R_SCL")
		)
	)
	(footprint ""
		(layer "B.Cu")
		(at 162.95624 -250.300236 90)
		(property "Reference" "C485"
			(at 0 0 90)
			(layer "B.SilkS")
			(hide yes)
			(effects
				(font
					(size 1.27 1.27)
				)
				(justify mirror)
			)
		)
		(property "Value" ""
			(at 0 0 90)
			(layer "B.Fab")
			(effects
				(font
					(size 1.27 1.27)
				)
				(justify mirror)
			)
		)
		(duplicate_pad_numbers_are_jumpers no)
		(fp_line
			(start 1.524 -0.762)
			(end -1.524 -0.762)
			(stroke
				(width 0.1524)
				(type default)
			)
			(layer "B.SilkS")
		)
		(fp_line
			(start -1.524 -0.762)
			(end -1.524 0.762)
			(stroke
				(width 0.1524)
				(type default)
			)
			(layer "B.SilkS")
		)
		(fp_line
			(start 1.524 0.762)
			(end 1.524 -0.762)
			(stroke
				(width 0.1524)
				(type default)
			)
			(layer "B.SilkS")
		)
		(fp_line
			(start -1.524 0.762)
			(end 1.524 0.762)
			(stroke
				(width 0.1524)
				(type default)
			)
			(layer "B.SilkS")
		)
		(fp_line
			(start 1.1049 -0.724916)
			(end 1.1049 0.724916)
			(stroke
				(width 0.1)
				(type default)
			)
			(layer "B.Fab")
		)
		(fp_line
			(start -1.1049 -0.724916)
			(end 1.1049 -0.724916)
			(stroke
				(width 0.1)
				(type default)
			)
			(layer "B.Fab")
		)
		(fp_line
			(start 1.1049 0.724916)
			(end -1.1049 0.724916)
			(stroke
				(width 0.1)
				(type default)
			)
			(layer "B.Fab")
		)
		(fp_line
			(start -1.1049 0.724916)
			(end -1.1049 -0.724916)
			(stroke
				(width 0.1)
				(type default)
			)
			(layer "B.Fab")
		)
		(pad "1" smd rect
			(at 0.889 0 90)
			(size 1.016 1.27)
			(layers "B.Cu" "B.Mask" "B.Paste")
			(net "PVCCFA_EHV_FIVRA_CPU1")
		)
		(pad "2" smd rect
			(at -0.889 0 90)
			(size 1.016 1.27)
			(layers "B.Cu" "B.Mask" "B.Paste")
			(net "GND")
		)
	)
)
